(kicad_pcb
	(version 20260206)
	(generator "pcbnew")
	(generator_version "10.0")
	(general
		(thickness 1.6)
		(legacy_teardrops no)
	)
	(paper "A4")
	(title_block
		(title "04192023_DAF0TMB3IC0_F0TG_MB_C_brd_V02_OCP.brd")
		(comment 1 "Grand Teton / footprints 2202-2207 of 8354")
	)
	(layers
		(0 "F.Cu" signal "TOP")
		(4 "In1.Cu" signal "GND")
		(6 "In2.Cu" signal "IN1")
		(8 "In3.Cu" signal "GND1")
		(10 "In4.Cu" signal "IN2")
		(12 "In5.Cu" signal "GND2")
		(14 "In6.Cu" signal "IN3")
		(16 "In7.Cu" signal "GND3")
		(18 "In8.Cu" signal "VCC")
		(20 "In9.Cu" signal "VCC1")
		(22 "In10.Cu" signal "GND4")
		(24 "In11.Cu" signal "IN4")
		(26 "In12.Cu" signal "GND5")
		(28 "In13.Cu" signal "IN5")
		(30 "In14.Cu" signal "GND6")
		(32 "In15.Cu" signal "IN6")
		(34 "In16.Cu" signal "GND7")
		(2 "B.Cu" signal "BOTTOM")
		(9 "F.Adhes" user "F.Adhesive")
		(11 "B.Adhes" user "B.Adhesive")
		(13 "F.Paste" user "Package Geometry/Pastemask Top")
		(15 "B.Paste" user "Package Geometry/Pastemask Bottom")
		(5 "F.SilkS" user "Ref Des/Silkscreen Top")
		(7 "B.SilkS" user "Ref Des/Silkscreen Bottom")
		(1 "F.Mask" user "Board Geometry/Soldermask Top")
		(3 "B.Mask" user "Board Geometry/Soldermask Bottom")
		(17 "Dwgs.User" user "User.Drawings")
		(19 "Cmts.User" user "User.Comments")
		(21 "Eco1.User" user "User.Eco1")
		(23 "Eco2.User" user "User.Eco2")
		(25 "Edge.Cuts" user "Board Geometry/Outline")
		(27 "Margin" user)
		(31 "F.CrtYd" user "Package Geometry/Place Bound Top")
		(29 "B.CrtYd" user "Package Geometry/Place Bound Bottom")
		(35 "F.Fab" user "Ref Des/Assembly Top")
		(33 "B.Fab" user "Ref Des/Assembly Bottom")
	)
	(footprint ""
		(layer "F.Cu")
		(at 331.653642 -142.293086 180)
		(property "Reference" "PR448"
			(at 0 0 180)
			(layer "F.SilkS")
			(hide yes)
			(effects
				(font
					(size 1.27 1.27)
				)
			)
		)
		(property "Value" ""
			(at 0 0 180)
			(layer "F.Fab")
			(effects
				(font
					(size 1.27 1.27)
				)
			)
		)
		(duplicate_pad_numbers_are_jumpers no)
		(fp_line
			(start 0.7874 0.4064)
			(end -0.7874 0.4064)
			(stroke
				(width 0.1524)
				(type default)
			)
			(layer "F.SilkS")
		)
		(fp_line
			(start 0.7874 -0.4064)
			(end 0.7874 0.4064)
			(stroke
				(width 0.1524)
				(type default)
			)
			(layer "F.SilkS")
		)
		(fp_line
			(start -0.7874 0.4064)
			(end -0.7874 -0.4064)
			(stroke
				(width 0.1524)
				(type default)
			)
			(layer "F.SilkS")
		)
		(fp_line
			(start -0.7874 -0.4064)
			(end 0.7874 -0.4064)
			(stroke
				(width 0.1524)
				(type default)
			)
			(layer "F.SilkS")
		)
		(fp_line
			(start 0.67945 0.3048)
			(end 0.120396 0.3048)
			(stroke
				(width 0.1)
				(type default)
			)
			(layer "F.Fab")
		)
		(fp_line
			(start 0.67945 -0.3048)
			(end 0.67945 0.3048)
			(stroke
				(width 0.1)
				(type default)
			)
			(layer "F.Fab")
		)
		(fp_line
			(start 0.12065 -0.2794)
			(end 0.12065 -0.3048)
			(stroke
				(width 0.1)
				(type default)
			)
			(layer "F.Fab")
		)
		(fp_line
			(start 0.12065 -0.3048)
			(end 0.67945 -0.3048)
			(stroke
				(width 0.1)
				(type default)
			)
			(layer "F.Fab")
		)
		(fp_line
			(start 0.120396 0.3048)
			(end 0.120396 0.2794)
			(stroke
				(width 0.1)
				(type default)
			)
			(layer "F.Fab")
		)
		(fp_line
			(start 0.120396 0.2794)
			(end -0.12065 0.2794)
			(stroke
				(width 0.1)
				(type default)
			)
			(layer "F.Fab")
		)
		(fp_line
			(start -0.12065 0.3048)
			(end -0.67945 0.3048)
			(stroke
				(width 0.1)
				(type default)
			)
			(layer "F.Fab")
		)
		(fp_line
			(start -0.12065 0.2794)
			(end -0.12065 0.3048)
			(stroke
				(width 0.1)
				(type default)
			)
			(layer "F.Fab")
		)
		(fp_line
			(start -0.12065 -0.2794)
			(end 0.12065 -0.2794)
			(stroke
				(width 0.1)
				(type default)
			)
			(layer "F.Fab")
		)
		(fp_line
			(start -0.12065 -0.305054)
			(end -0.12065 -0.2794)
			(stroke
				(width 0.1)
				(type default)
			)
			(layer "F.Fab")
		)
		(fp_line
			(start -0.67945 0.3048)
			(end -0.67945 -0.305054)
			(stroke
				(width 0.1)
				(type default)
			)
			(layer "F.Fab")
		)
		(fp_line
			(start -0.67945 -0.305054)
			(end -0.12065 -0.305054)
			(stroke
				(width 0.1)
				(type default)
			)
			(layer "F.Fab")
		)
		(pad "1" smd circle
			(at -0.40005 0 180)
			(size 0 0)
			(layers "F.Cu" "F.Mask" "F.Paste")
			(net "PVDD18_S5_P0_CS")
		)
		(pad "2" smd circle
			(at 0.40005 0 180)
			(size 0 0)
			(layers "F.Cu" "F.Mask" "F.Paste")
			(net "GND")
		)
	)
	(footprint ""
		(layer "F.Cu")
		(at 329.355958 -194.052952 -90)
		(property "Reference" "R357"
			(at 0 0 270)
			(layer "F.SilkS")
			(hide yes)
			(effects
				(font
					(size 1.27 1.27)
				)
			)
		)
		(property "Value" ""
			(at 0 0 270)
			(layer "F.Fab")
			(effects
				(font
					(size 1.27 1.27)
				)
			)
		)
		(duplicate_pad_numbers_are_jumpers no)
		(fp_line
			(start -0.7874 0.4064)
			(end -0.7874 -0.4064)
			(stroke
				(width 0.1524)
				(type default)
			)
			(layer "F.SilkS")
		)
		(fp_line
			(start 0.7874 0.4064)
			(end -0.7874 0.4064)
			(stroke
				(width 0.1524)
				(type default)
			)
			(layer "F.SilkS")
		)
		(fp_line
			(start -0.7874 -0.4064)
			(end 0.7874 -0.4064)
			(stroke
				(width 0.1524)
				(type default)
			)
			(layer "F.SilkS")
		)
		(fp_line
			(start 0.7874 -0.4064)
			(end 0.7874 0.4064)
			(stroke
				(width 0.1524)
				(type default)
			)
			(layer "F.SilkS")
		)
		(fp_line
			(start -0.67945 0.3048)
			(end -0.67945 -0.305054)
			(stroke
				(width 0.1)
				(type default)
			)
			(layer "F.Fab")
		)
		(fp_line
			(start -0.12065 0.3048)
			(end -0.67945 0.3048)
			(stroke
				(width 0.1)
				(type default)
			)
			(layer "F.Fab")
		)
		(fp_line
			(start 0.120396 0.3048)
			(end 0.120396 0.2794)
			(stroke
				(width 0.1)
				(type default)
			)
			(layer "F.Fab")
		)
		(fp_line
			(start 0.67945 0.3048)
			(end 0.120396 0.3048)
			(stroke
				(width 0.1)
				(type default)
			)
			(layer "F.Fab")
		)
		(fp_line
			(start -0.12065 0.2794)
			(end -0.12065 0.3048)
			(stroke
				(width 0.1)
				(type default)
			)
			(layer "F.Fab")
		)
		(fp_line
			(start 0.120396 0.2794)
			(end -0.12065 0.2794)
			(stroke
				(width 0.1)
				(type default)
			)
			(layer "F.Fab")
		)
		(fp_line
			(start -0.12065 -0.2794)
			(end 0.12065 -0.2794)
			(stroke
				(width 0.1)
				(type default)
			)
			(layer "F.Fab")
		)
		(fp_line
			(start 0.12065 -0.2794)
			(end 0.12065 -0.3048)
			(stroke
				(width 0.1)
				(type default)
			)
			(layer "F.Fab")
		)
		(fp_line
			(start 0.12065 -0.3048)
			(end 0.67945 -0.3048)
			(stroke
				(width 0.1)
				(type default)
			)
			(layer "F.Fab")
		)
		(fp_line
			(start 0.67945 -0.3048)
			(end 0.67945 0.3048)
			(stroke
				(width 0.1)
				(type default)
			)
			(layer "F.Fab")
		)
		(fp_line
			(start -0.67945 -0.305054)
			(end -0.12065 -0.305054)
			(stroke
				(width 0.1)
				(type default)
			)
			(layer "F.Fab")
		)
		(fp_line
			(start -0.12065 -0.305054)
			(end -0.12065 -0.2794)
			(stroke
				(width 0.1)
				(type default)
			)
			(layer "F.Fab")
		)
		(pad "1" smd circle
			(at -0.40005 0 270)
			(size 0 0)
			(layers "F.Cu" "F.Mask" "F.Paste")
			(net "CPU0_XTRIG_R2_L7")
		)
		(pad "2" smd circle
			(at 0.40005 0 270)
			(size 0 0)
			(layers "F.Cu" "F.Mask" "F.Paste")
			(net "CPU0_XTRIG_L7")
		)
	)
	(footprint ""
		(layer "F.Cu")
		(at 205.25105 -107.362498)
		(property "Reference" "C5016"
			(at 0 0 0)
			(layer "F.SilkS")
			(hide yes)
			(effects
				(font
					(size 1.27 1.27)
				)
			)
		)
		(property "Value" ""
			(at 0 0 0)
			(layer "F.Fab")
			(effects
				(font
					(size 1.27 1.27)
				)
			)
		)
		(duplicate_pad_numbers_are_jumpers no)
		(fp_line
			(start -0.7874 -0.4064)
			(end 0.7874 -0.4064)
			(stroke
				(width 0.1524)
				(type default)
			)
			(layer "F.SilkS")
		)
		(fp_line
			(start -0.7874 0.4064)
			(end -0.7874 -0.4064)
			(stroke
				(width 0.1524)
				(type default)
			)
			(layer "F.SilkS")
		)
		(fp_line
			(start 0.7874 -0.4064)
			(end 0.7874 0.4064)
			(stroke
				(width 0.1524)
				(type default)
			)
			(layer "F.SilkS")
		)
		(fp_line
			(start 0.7874 0.4064)
			(end -0.7874 0.4064)
			(stroke
				(width 0.1524)
				(type default)
			)
			(layer "F.SilkS")
		)
		(fp_line
			(start -0.67945 -0.305054)
			(end -0.12065 -0.305054)
			(stroke
				(width 0.1)
				(type default)
			)
			(layer "F.Fab")
		)
		(fp_line
			(start -0.67945 0.3048)
			(end -0.67945 -0.305054)
			(stroke
				(width 0.1)
				(type default)
			)
			(layer "F.Fab")
		)
		(fp_line
			(start -0.12065 -0.305054)
			(end -0.12065 -0.2794)
			(stroke
				(width 0.1)
				(type default)
			)
			(layer "F.Fab")
		)
		(fp_line
			(start -0.12065 -0.2794)
			(end 0.12065 -0.2794)
			(stroke
				(width 0.1)
				(type default)
			)
			(layer "F.Fab")
		)
		(fp_line
			(start -0.12065 0.2794)
			(end -0.12065 0.3048)
			(stroke
				(width 0.1)
				(type default)
			)
			(layer "F.Fab")
		)
		(fp_line
			(start -0.12065 0.3048)
			(end -0.67945 0.3048)
			(stroke
				(width 0.1)
				(type default)
			)
			(layer "F.Fab")
		)
		(fp_line
			(start 0.120396 0.2794)
			(end -0.12065 0.2794)
			(stroke
				(width 0.1)
				(type default)
			)
			(layer "F.Fab")
		)
		(fp_line
			(start 0.120396 0.3048)
			(end 0.120396 0.2794)
			(stroke
				(width 0.1)
				(type default)
			)
			(layer "F.Fab")
		)
		(fp_line
			(start 0.12065 -0.3048)
			(end 0.67945 -0.3048)
			(stroke
				(width 0.1)
				(type default)
			)
			(layer "F.Fab")
		)
		(fp_line
			(start 0.12065 -0.2794)
			(end 0.12065 -0.3048)
			(stroke
				(width 0.1)
				(type default)
			)
			(layer "F.Fab")
		)
		(fp_line
			(start 0.67945 -0.3048)
			(end 0.67945 0.3048)
			(stroke
				(width 0.1)
				(type default)
			)
			(layer "F.Fab")
		)
		(fp_line
			(start 0.67945 0.3048)
			(end 0.120396 0.3048)
			(stroke
				(width 0.1)
				(type default)
			)
			(layer "F.Fab")
		)
		(pad "1" smd circle
			(at -0.40005 0)
			(size 0 0)
			(layers "F.Cu" "F.Mask" "F.Paste")
			(net "PWRGD_PVDD18_S5_R_P1")
		)
		(pad "2" smd circle
			(at 0.40005 0)
			(size 0 0)
			(layers "F.Cu" "F.Mask" "F.Paste")
			(net "GND")
		)
	)
	(footprint ""
		(layer "F.Cu")
		(at 398.069562 -397.726154 180)
		(property "Reference" "R1413"
			(at 0 0 180)
			(layer "F.SilkS")
			(hide yes)
			(effects
				(font
					(size 1.27 1.27)
				)
			)
		)
		(property "Value" ""
			(at 0 0 180)
			(layer "F.Fab")
			(effects
				(font
					(size 1.27 1.27)
				)
			)
		)
		(duplicate_pad_numbers_are_jumpers no)
		(fp_line
			(start 0.32512 0.175006)
			(end -0.32512 0.175006)
			(stroke
				(width 0.1)
				(type default)
			)
			(layer "F.Fab")
		)
		(fp_line
			(start 0.32512 -0.175006)
			(end 0.32512 0.175006)
			(stroke
				(width 0.1)
				(type default)
			)
			(layer "F.Fab")
		)
		(fp_line
			(start -0.32512 0.175006)
			(end -0.32512 -0.175006)
			(stroke
				(width 0.1)
				(type default)
			)
			(layer "F.Fab")
		)
		(fp_line
			(start -0.32512 -0.175006)
			(end 0.32512 -0.175006)
			(stroke
				(width 0.1)
				(type default)
			)
			(layer "F.Fab")
		)
		(pad "1" smd rect
			(at -0.2667 0 180)
			(size 0.3048 0.381)
			(layers "F.Cu" "F.Mask" "F.Paste")
			(net "P1V8_CPU0_RT_1D")
		)
		(pad "2" smd rect
			(at 0.2667 0)
			(size 0.3048 0.381)
			(layers "F.Cu" "F.Mask" "F.Paste")
			(net "RXDET_BYP_RT_CPU0_P3")
		)
	)
	(footprint ""
		(layer "F.Cu")
		(at 299.543724 -395.066774 -90)
		(property "Reference" "R623"
			(at 0 0 270)
			(layer "F.SilkS")
			(hide yes)
			(effects
				(font
					(size 1.27 1.27)
				)
			)
		)
		(property "Value" ""
			(at 0 0 270)
			(layer "F.Fab")
			(effects
				(font
					(size 1.27 1.27)
				)
			)
		)
		(duplicate_pad_numbers_are_jumpers no)
		(fp_line
			(start -0.32512 0.175006)
			(end -0.32512 -0.175006)
			(stroke
				(width 0.1)
				(type default)
			)
			(layer "F.Fab")
		)
		(fp_line
			(start 0.32512 0.175006)
			(end -0.32512 0.175006)
			(stroke
				(width 0.1)
				(type default)
			)
			(layer "F.Fab")
		)
		(fp_line
			(start -0.32512 -0.175006)
			(end 0.32512 -0.175006)
			(stroke
				(width 0.1)
				(type default)
			)
			(layer "F.Fab")
		)
		(fp_line
			(start 0.32512 -0.175006)
			(end 0.32512 0.175006)
			(stroke
				(width 0.1)
				(type default)
			)
			(layer "F.Fab")
		)
		(pad "1" smd rect
			(at -0.2667 0 270)
			(size 0.3048 0.381)
			(layers "F.Cu" "F.Mask" "F.Paste")
			(net "CLK_100M_RETIMER_CPU0_P0_DN")
		)
		(pad "2" smd rect
			(at 0.2667 0 90)
			(size 0.3048 0.381)
			(layers "F.Cu" "F.Mask" "F.Paste")
			(net "GND")
		)
	)
	(footprint ""
		(layer "F.Cu")
		(at 440.78525 6.149848 180)
		(property "Reference" "J66"
			(at -4.541266 -1.222756 90)
			(unlocked yes)
			(layer "F.SilkS")
			(effects
				(font
					(size 0.7874 0.5842)
					(thickness 0.1524)
				)
				(justify left)
			)
		)
		(property "Value" ""
			(at 0 0 180)
			(layer "F.Fab")
			(effects
				(font
					(size 1.27 1.27)
				)
			)
		)
		(duplicate_pad_numbers_are_jumpers no)
		(fp_line
			(start 1.2192 2.06756)
			(end -1.2192 2.06756)
			(stroke
				(width 0.1524)
				(type default)
			)
			(layer "F.SilkS")
		)
		(fp_line
			(start 1.2192 -2.06756)
			(end 1.2192 2.06756)
			(stroke
				(width 0.1524)
				(type default)
			)
			(layer "F.SilkS")
		)
		(fp_line
			(start -1.2192 2.06756)
			(end -1.2192 -2.06756)
			(stroke
				(width 0.1524)
				(type default)
			)
			(layer "F.SilkS")
		)
		(fp_line
			(start -1.2192 -2.06756)
			(end 1.2192 -2.06756)
			(stroke
				(width 0.1524)
				(type default)
			)
			(layer "F.SilkS")
		)
		(pad "" np_thru_hole circle
			(at -2.8829 -1.27 90)
			(size 1.0414 1.0414)
			(drill 1.0414)
			(layers "*.Cu" "*.Mask")
			(clearance 0.381)
			(thermal_gap 0.381)
		)
		(pad "" np_thru_hole circle
			(at -2.8829 1.27 90)
			(size 1.0414 1.0414)
			(drill 1.0414)
			(layers "*.Cu" "*.Mask")
			(clearance 0.381)
			(thermal_gap 0.381)
		)
		(pad "" np_thru_hole circle
			(at 3.4671 -1.27 90)
			(size 1.0414 1.0414)
			(drill 1.0414)
			(layers "*.Cu" "*.Mask")
			(clearance 0.381)
			(thermal_gap 0.381)
		)
		(pad "" np_thru_hole circle
			(at 3.4671 1.27 90)
			(size 1.0414 1.0414)
			(drill 1.0414)
			(layers "*.Cu" "*.Mask")
			(clearance 0.381)
			(thermal_gap 0.381)
		)
		(pad "1" smd rect
			(at 0.8255 -0.249936 90)
			(size 0.3048 0.508)
			(layers "F.Cu" "F.Mask" "F.Paste")
			(net "DELTA_L_85_5INCH_IN2_DP")
		)
		(pad "2" smd rect
			(at 0.8255 0.249936 90)
			(size 0.3048 0.508)
			(layers "F.Cu" "F.Mask" "F.Paste")
			(net "DELTA_L_85_5INCH_IN2_DN")
		)
		(pad "3" smd circle
			(at 0 0 180)
			(size 0 0)
			(layers "F.Cu" "F.Mask" "F.Paste")
			(net "DELTA_L_GND_1")
		)
		(zone
			(layer "F.Cu")
			(hatch none 0.5)
			(connect_pads
				(clearance 0)
			)
			(min_thickness 0.25)
			(keepout
				(tracks not_allowed)
				(vias allowed)
				(pads allowed)
				(copperpour not_allowed)
				(footprints allowed)
			)
			(placement
				(enabled no)
				(sheetname "")
			)
			(fill
				(thermal_gap 0.5)
				(thermal_bridge_width 0.5)
				(island_removal_mode 0)
			)
			(polygon
				(pts
					(xy 439.66765 6.698488) (xy 439.66765 6.602984) (xy 440.26455 6.602984) (xy 440.26455 6.196584)
					(xy 439.66765 6.196584) (xy 439.66765 6.103112) (xy 440.26455 6.103112) (xy 440.26455 5.696712)
					(xy 439.66765 5.696712) (xy 439.66765 5.601208) (xy 440.36615 5.601208) (xy 440.36615 6.698488)
				)
			)
		)
		(zone
			(layers "F.Cu" "B.Cu" "In1.Cu" "In2.Cu" "In3.Cu" "In4.Cu" "In5.Cu" "In6.Cu"
				"In7.Cu" "In8.Cu" "In9.Cu" "In10.Cu" "In11.Cu" "In12.Cu" "In13.Cu" "In14.Cu"
				"In15.Cu" "In16.Cu"
			)
			(hatch none 0.5)
			(connect_pads
				(clearance 0)
			)
			(min_thickness 0.25)
			(keepout
				(tracks not_allowed)
				(vias allowed)
				(pads allowed)
				(copperpour not_allowed)
				(footprints allowed)
			)
			(placement
				(enabled no)
				(sheetname "")
			)
			(fill
				(thermal_gap 0.5)
				(thermal_bridge_width 0.5)
				(island_removal_mode 0)
			)
			(polygon
				(pts
					(arc
						(start 438.24525 4.879848)
						(mid 436.39105 4.879848)
						(end 438.24525 4.879848)
					)
				)
			)
		)
		(zone
			(layers "F.Cu" "B.Cu" "In1.Cu" "In2.Cu" "In3.Cu" "In4.Cu" "In5.Cu" "In6.Cu"
				"In7.Cu" "In8.Cu" "In9.Cu" "In10.Cu" "In11.Cu" "In12.Cu" "In13.Cu" "In14.Cu"
				"In15.Cu" "In16.Cu"
			)
			(hatch none 0.5)
			(connect_pads
				(clearance 0)
			)
			(min_thickness 0.25)
			(keepout
				(tracks not_allowed)
				(vias allowed)
				(pads allowed)
				(copperpour not_allowed)
				(footprints allowed)
			)
			(placement
				(enabled no)
				(sheetname "")
			)
			(fill
				(thermal_gap 0.5)
				(thermal_bridge_width 0.5)
				(island_removal_mode 0)
			)
			(polygon
				(pts
					(arc
						(start 438.24525 7.419848)
						(mid 436.39105 7.419848)
						(end 438.24525 7.419848)
					)
				)
			)
		)
		(zone
			(layers "F.Cu" "B.Cu" "In1.Cu" "In2.Cu" "In3.Cu" "In4.Cu" "In5.Cu" "In6.Cu"
				"In7.Cu" "In8.Cu" "In9.Cu" "In10.Cu" "In11.Cu" "In12.Cu" "In13.Cu" "In14.Cu"
				"In15.Cu" "In16.Cu"
			)
			(hatch none 0.5)
			(connect_pads
				(clearance 0)
			)
			(min_thickness 0.25)
			(keepout
				(tracks not_allowed)
				(vias allowed)
				(pads allowed)
				(copperpour not_allowed)
				(footprints allowed)
			)
			(placement
				(enabled no)
				(sheetname "")
			)
			(fill
				(thermal_gap 0.5)
				(thermal_bridge_width 0.5)
				(island_removal_mode 0)
			)
			(polygon
				(pts
					(arc
						(start 444.59525 4.879848)
						(mid 442.74105 4.879848)
						(end 444.59525 4.879848)
					)
				)
			)
		)
		(zone
			(layers "F.Cu" "B.Cu" "In1.Cu" "In2.Cu" "In3.Cu" "In4.Cu" "In5.Cu" "In6.Cu"
				"In7.Cu" "In8.Cu" "In9.Cu" "In10.Cu" "In11.Cu" "In12.Cu" "In13.Cu" "In14.Cu"
				"In15.Cu" "In16.Cu"
			)
			(hatch none 0.5)
			(connect_pads
				(clearance 0)
			)
			(min_thickness 0.25)
			(keepout
				(tracks not_allowed)
				(vias allowed)
				(pads allowed)
				(copperpour not_allowed)
				(footprints allowed)
			)
			(placement
				(enabled no)
				(sheetname "")
			)
			(fill
				(thermal_gap 0.5)
				(thermal_bridge_width 0.5)
				(island_removal_mode 0)
			)
			(polygon
				(pts
					(arc
						(start 444.59525 7.419848)
						(mid 442.74105 7.419848)
						(end 444.59525 7.419848)
					)
				)
			)
		)
	)
)
